(kicad_pcb
	(version 20260206)
	(generator "pcbnew")
	(generator_version "10.0")
	(general
		(thickness 1.6)
		(legacy_teardrops no)
	)
	(paper "A4")
	(title_block
		(title "Wiwynn_Tioga_Pass_MB.brd")
		(comment 1 "Tioga Pass / footprints 4447-4453 of 4770")
	)
	(layers
		(0 "F.Cu" signal "TOP")
		(4 "In1.Cu" signal "L2GND")
		(6 "In2.Cu" signal "L3")
		(8 "In3.Cu" signal "L4GND")
		(10 "In4.Cu" signal "L5")
		(12 "In5.Cu" signal "L6GND")
		(14 "In6.Cu" signal "L7VCC")
		(16 "In7.Cu" signal "L8VCC")
		(18 "In8.Cu" signal "L9GND")
		(20 "In9.Cu" signal "L10")
		(22 "In10.Cu" signal "L11GND")
		(24 "In11.Cu" signal "L12")
		(26 "In12.Cu" signal "L13GND")
		(2 "B.Cu" signal "BOTTOM")
		(9 "F.Adhes" user "F.Adhesive")
		(11 "B.Adhes" user "B.Adhesive")
		(13 "F.Paste" user "Package Geometry/Pastemask Top")
		(15 "B.Paste" user "Package Geometry/Pastemask Bottom")
		(5 "F.SilkS" user "Ref Des/Silkscreen Top")
		(7 "B.SilkS" user "Ref Des/Silkscreen Bottom")
		(1 "F.Mask" user "Board Geometry/Soldermask Top")
		(3 "B.Mask" user "Board Geometry/Soldermask Bottom")
		(17 "Dwgs.User" user "User.Drawings")
		(19 "Cmts.User" user "User.Comments")
		(21 "Eco1.User" user "User.Eco1")
		(23 "Eco2.User" user "User.Eco2")
		(25 "Edge.Cuts" user "Board Geometry/Outline")
		(27 "Margin" user)
		(31 "F.CrtYd" user "Package Geometry/Place Bound Top")
		(29 "B.CrtYd" user "Package Geometry/Place Bound Bottom")
		(35 "F.Fab" user "Ref Des/Assembly Top")
		(33 "B.Fab" user "Ref Des/Assembly Bottom")
	)
	(footprint ""
		(layer "B.Cu")
		(at 394.175234 -150.95474 -90)
		(property "Reference" "R2L14"
			(at 0 0 90)
			(layer "B.SilkS")
			(hide yes)
			(effects
				(font
					(size 1.27 1.27)
				)
				(justify mirror)
			)
		)
		(property "Value" ""
			(at 0 0 90)
			(layer "B.Fab")
			(effects
				(font
					(size 1.27 1.27)
				)
				(justify mirror)
			)
		)
		(duplicate_pad_numbers_are_jumpers no)
		(fp_poly
			(pts
				(xy 0.2794 -0.1016) (xy -0.2794 -0.1016) (xy -0.2794 0.9906) (xy 0.2794 0.9906)
			)
			(stroke
				(width 0)
				(type default)
			)
			(fill no)
			(layer "B.CrtYd")
		)
		(fp_line
			(start -0.2794 0.9906)
			(end -0.2794 -0.1016)
			(stroke
				(width 0.1)
				(type default)
			)
			(layer "B.Fab")
		)
		(fp_line
			(start 0.2794 0.9906)
			(end -0.2794 0.9906)
			(stroke
				(width 0.1)
				(type default)
			)
			(layer "B.Fab")
		)
		(fp_line
			(start -0.2794 -0.1016)
			(end 0.2794 -0.1016)
			(stroke
				(width 0.1)
				(type default)
			)
			(layer "B.Fab")
		)
		(fp_line
			(start 0.2794 -0.1016)
			(end 0.2794 0.9906)
			(stroke
				(width 0.1)
				(type default)
			)
			(layer "B.Fab")
		)
		(pad "1" smd rect
			(at 0 0 90)
			(size 0.508 0.508)
			(layers "B.Cu" "B.Mask" "B.Paste")
			(net "P3V3_STBY")
		)
		(pad "2" smd rect
			(at 0 0.889 90)
			(size 0.508 0.508)
			(layers "B.Cu" "B.Mask" "B.Paste")
			(net "VR_PVNN_PCH_VDD")
		)
		(zone
			(layer "B.Cu")
			(hatch none 0.5)
			(connect_pads
				(clearance 0)
			)
			(min_thickness 0.25)
			(keepout
				(tracks not_allowed)
				(vias allowed)
				(pads allowed)
				(copperpour not_allowed)
				(footprints allowed)
			)
			(placement
				(enabled no)
				(sheetname "")
			)
			(fill
				(thermal_gap 0.5)
				(thermal_bridge_width 0.5)
				(island_removal_mode 0)
			)
			(polygon
				(pts
					(xy 393.540234 -150.70074) (xy 393.540234 -151.20874) (xy 393.921234 -151.20874) (xy 393.921234 -150.70074)
				)
			)
		)
		(zone
			(layer "B.Cu")
			(hatch none 0.5)
			(connect_pads
				(clearance 0)
			)
			(min_thickness 0.25)
			(keepout
				(tracks allowed)
				(vias not_allowed)
				(pads allowed)
				(copperpour not_allowed)
				(footprints allowed)
			)
			(placement
				(enabled no)
				(sheetname "")
			)
			(fill
				(thermal_gap 0.5)
				(thermal_bridge_width 0.5)
				(island_removal_mode 0)
			)
			(polygon
				(pts
					(xy 393.921234 -150.70074) (xy 393.921234 -151.20874) (xy 393.540234 -151.20874) (xy 393.540234 -150.70074)
				)
			)
		)
	)
	(footprint ""
		(layer "B.Cu")
		(at 362.270294 -46.433486 180)
		(property "Reference" "R7D41"
			(at 0 0 0)
			(layer "B.SilkS")
			(hide yes)
			(effects
				(font
					(size 1.27 1.27)
				)
				(justify mirror)
			)
		)
		(property "Value" ""
			(at 0 0 0)
			(layer "B.Fab")
			(effects
				(font
					(size 1.27 1.27)
				)
				(justify mirror)
			)
		)
		(duplicate_pad_numbers_are_jumpers no)
		(fp_poly
			(pts
				(xy 0.2794 -0.1016) (xy -0.2794 -0.1016) (xy -0.2794 0.9906) (xy 0.2794 0.9906)
			)
			(stroke
				(width 0)
				(type default)
			)
			(fill no)
			(layer "B.CrtYd")
		)
		(fp_line
			(start 0.2794 0.9906)
			(end -0.2794 0.9906)
			(stroke
				(width 0.1)
				(type default)
			)
			(layer "B.Fab")
		)
		(fp_line
			(start 0.2794 -0.1016)
			(end 0.2794 0.9906)
			(stroke
				(width 0.1)
				(type default)
			)
			(layer "B.Fab")
		)
		(fp_line
			(start -0.2794 0.9906)
			(end -0.2794 -0.1016)
			(stroke
				(width 0.1)
				(type default)
			)
			(layer "B.Fab")
		)
		(fp_line
			(start -0.2794 -0.1016)
			(end 0.2794 -0.1016)
			(stroke
				(width 0.1)
				(type default)
			)
			(layer "B.Fab")
		)
		(pad "1" smd rect
			(at 0 0)
			(size 0.508 0.508)
			(layers "B.Cu" "B.Mask" "B.Paste")
			(net "FM_CPU1_PROCHOT_LVT3_R_N")
		)
		(pad "2" smd rect
			(at 0 0.889)
			(size 0.508 0.508)
			(layers "B.Cu" "B.Mask" "B.Paste")
			(net "FM_CPU1_PROCHOT_LVT3_K_N")
		)
		(zone
			(layer "B.Cu")
			(hatch none 0.5)
			(connect_pads
				(clearance 0)
			)
			(min_thickness 0.25)
			(keepout
				(tracks not_allowed)
				(vias allowed)
				(pads allowed)
				(copperpour not_allowed)
				(footprints allowed)
			)
			(placement
				(enabled no)
				(sheetname "")
			)
			(fill
				(thermal_gap 0.5)
				(thermal_bridge_width 0.5)
				(island_removal_mode 0)
			)
			(polygon
				(pts
					(xy 362.016294 -47.068486) (xy 362.524294 -47.068486) (xy 362.524294 -46.687486) (xy 362.016294 -46.687486)
				)
			)
		)
		(zone
			(layer "B.Cu")
			(hatch none 0.5)
			(connect_pads
				(clearance 0)
			)
			(min_thickness 0.25)
			(keepout
				(tracks allowed)
				(vias not_allowed)
				(pads allowed)
				(copperpour not_allowed)
				(footprints allowed)
			)
			(placement
				(enabled no)
				(sheetname "")
			)
			(fill
				(thermal_gap 0.5)
				(thermal_bridge_width 0.5)
				(island_removal_mode 0)
			)
			(polygon
				(pts
					(xy 362.016294 -46.687486) (xy 362.524294 -46.687486) (xy 362.524294 -47.068486) (xy 362.016294 -47.068486)
				)
			)
		)
	)
	(footprint ""
		(layer "B.Cu")
		(at 361.188 -23.241)
		(property "Reference" "C3T15"
			(at -3.20167 3.81 270)
			(unlocked yes)
			(layer "B.SilkS")
			(effects
				(font
					(size 0.7874 0.5842)
					(thickness 0.1524)
				)
				(justify mirror)
			)
		)
		(property "Value" ""
			(at 0 0 0)
			(layer "B.Fab")
			(effects
				(font
					(size 1.27 1.27)
				)
				(justify mirror)
			)
		)
		(duplicate_pad_numbers_are_jumpers no)
		(fp_line
			(start -2.504948 -1.616456)
			(end -2.504948 1.633728)
			(stroke
				(width 0.1524)
				(type default)
			)
			(layer "B.SilkS")
		)
		(fp_line
			(start -2.504948 1.633728)
			(end -1.6002 1.633728)
			(stroke
				(width 0.1524)
				(type default)
			)
			(layer "B.SilkS")
		)
		(fp_line
			(start -2.286 7.366)
			(end -2.286 1.63195)
			(stroke
				(width 0.1524)
				(type default)
			)
			(layer "B.SilkS")
		)
		(fp_line
			(start -2.286 7.366)
			(end -1.600708 7.366)
			(stroke
				(width 0.1524)
				(type default)
			)
			(layer "B.SilkS")
		)
		(fp_line
			(start -1.6002 -1.616456)
			(end -2.504948 -1.616456)
			(stroke
				(width 0.1524)
				(type default)
			)
			(layer "B.SilkS")
		)
		(fp_line
			(start 1.6002 -1.616456)
			(end 2.563114 -1.616456)
			(stroke
				(width 0.1524)
				(type default)
			)
			(layer "B.SilkS")
		)
		(fp_line
			(start 2.286 7.366)
			(end 1.60147 7.366)
			(stroke
				(width 0.1524)
				(type default)
			)
			(layer "B.SilkS")
		)
		(fp_line
			(start 2.286 7.366)
			(end 2.286 1.632712)
			(stroke
				(width 0.1524)
				(type default)
			)
			(layer "B.SilkS")
		)
		(fp_line
			(start 2.563114 -1.616456)
			(end 2.563114 1.633728)
			(stroke
				(width 0.1524)
				(type default)
			)
			(layer "B.SilkS")
		)
		(fp_line
			(start 2.563114 1.633728)
			(end 1.6002 1.633728)
			(stroke
				(width 0.1524)
				(type default)
			)
			(layer "B.SilkS")
		)
		(fp_rect
			(start 2.286 7.366)
			(end -2.286 -0.254)
			(stroke
				(width 0)
				(type default)
			)
			(fill no)
			(layer "B.CrtYd")
		)
		(fp_line
			(start -2.286 -0.254)
			(end -2.286 7.366)
			(stroke
				(width 0.1)
				(type default)
			)
			(layer "B.Fab")
		)
		(fp_line
			(start -2.286 7.366)
			(end 2.286 7.366)
			(stroke
				(width 0.1)
				(type default)
			)
			(layer "B.Fab")
		)
		(fp_line
			(start 2.286 -0.254)
			(end -2.286 -0.254)
			(stroke
				(width 0.1)
				(type default)
			)
			(layer "B.Fab")
		)
		(fp_line
			(start 2.286 7.366)
			(end 2.286 -0.254)
			(stroke
				(width 0.1)
				(type default)
			)
			(layer "B.Fab")
		)
		(pad "1" smd rect
			(at 0 0 180)
			(size 2.54 3.048)
			(layers "B.Cu" "B.Mask" "B.Paste")
			(net "P12V_STBY")
		)
		(pad "2" smd rect
			(at 0 7.112 180)
			(size 2.54 3.048)
			(layers "B.Cu" "B.Mask" "B.Paste")
			(net "GND")
		)
	)
	(footprint ""
		(layer "B.Cu")
		(at 18.0086 -139.1666 -90)
		(property "Reference" "C9L12"
			(at -2.03073 9.6266 0)
			(unlocked yes)
			(layer "B.SilkS")
			(effects
				(font
					(size 0.7874 0.5842)
					(thickness 0.1524)
				)
				(justify mirror)
			)
		)
		(property "Value" ""
			(at 0 0 90)
			(layer "B.Fab")
			(effects
				(font
					(size 1.27 1.27)
				)
				(justify mirror)
			)
		)
		(duplicate_pad_numbers_are_jumpers no)
		(fp_line
			(start -2.286 7.366)
			(end -1.600708 7.366)
			(stroke
				(width 0.1524)
				(type default)
			)
			(layer "B.SilkS")
		)
		(fp_line
			(start -2.286 7.366)
			(end -2.286 1.63195)
			(stroke
				(width 0.1524)
				(type default)
			)
			(layer "B.SilkS")
		)
		(fp_line
			(start 2.286 7.366)
			(end 1.60147 7.366)
			(stroke
				(width 0.1524)
				(type default)
			)
			(layer "B.SilkS")
		)
		(fp_line
			(start 2.286 7.366)
			(end 2.286 1.632712)
			(stroke
				(width 0.1524)
				(type default)
			)
			(layer "B.SilkS")
		)
		(fp_line
			(start -2.504948 1.633728)
			(end -1.6002 1.633728)
			(stroke
				(width 0.1524)
				(type default)
			)
			(layer "B.SilkS")
		)
		(fp_line
			(start 2.563114 1.633728)
			(end 1.6002 1.633728)
			(stroke
				(width 0.1524)
				(type default)
			)
			(layer "B.SilkS")
		)
		(fp_line
			(start -2.504948 -1.616456)
			(end -2.504948 1.633728)
			(stroke
				(width 0.1524)
				(type default)
			)
			(layer "B.SilkS")
		)
		(fp_line
			(start -1.6002 -1.616456)
			(end -2.504948 -1.616456)
			(stroke
				(width 0.1524)
				(type default)
			)
			(layer "B.SilkS")
		)
		(fp_line
			(start 1.6002 -1.616456)
			(end 2.563114 -1.616456)
			(stroke
				(width 0.1524)
				(type default)
			)
			(layer "B.SilkS")
		)
		(fp_line
			(start 2.563114 -1.616456)
			(end 2.563114 1.633728)
			(stroke
				(width 0.1524)
				(type default)
			)
			(layer "B.SilkS")
		)
		(fp_rect
			(start 2.286 -0.254)
			(end -2.286 7.366)
			(stroke
				(width 0)
				(type default)
			)
			(fill no)
			(layer "B.CrtYd")
		)
		(fp_line
			(start -2.286 7.366)
			(end 2.286 7.366)
			(stroke
				(width 0.1)
				(type default)
			)
			(layer "B.Fab")
		)
		(fp_line
			(start 2.286 7.366)
			(end 2.286 -0.254)
			(stroke
				(width 0.1)
				(type default)
			)
			(layer "B.Fab")
		)
		(fp_line
			(start -2.286 -0.254)
			(end -2.286 7.366)
			(stroke
				(width 0.1)
				(type default)
			)
			(layer "B.Fab")
		)
		(fp_line
			(start 2.286 -0.254)
			(end -2.286 -0.254)
			(stroke
				(width 0.1)
				(type default)
			)
			(layer "B.Fab")
		)
		(pad "1" smd rect
			(at 0 0 90)
			(size 2.54 3.048)
			(layers "B.Cu" "B.Mask" "B.Paste")
			(net "PVDDQ_KLM")
		)
		(pad "2" smd rect
			(at 0 7.112 90)
			(size 2.54 3.048)
			(layers "B.Cu" "B.Mask" "B.Paste")
			(net "GND")
		)
	)
	(footprint ""
		(layer "B.Cu")
		(at 323.8627 -28.36418 -90)
		(property "Reference" "R4T7"
			(at 0 0 90)
			(layer "B.SilkS")
			(hide yes)
			(effects
				(font
					(size 1.27 1.27)
				)
				(justify mirror)
			)
		)
		(property "Value" ""
			(at 0 0 90)
			(layer "B.Fab")
			(effects
				(font
					(size 1.27 1.27)
				)
				(justify mirror)
			)
		)
		(duplicate_pad_numbers_are_jumpers no)
		(fp_poly
			(pts
				(xy 0.2794 -0.1016) (xy -0.2794 -0.1016) (xy -0.2794 0.9906) (xy 0.2794 0.9906)
			)
			(stroke
				(width 0)
				(type default)
			)
			(fill no)
			(layer "B.CrtYd")
		)
		(fp_line
			(start -0.2794 0.9906)
			(end -0.2794 -0.1016)
			(stroke
				(width 0.1)
				(type default)
			)
			(layer "B.Fab")
		)
		(fp_line
			(start 0.2794 0.9906)
			(end -0.2794 0.9906)
			(stroke
				(width 0.1)
				(type default)
			)
			(layer "B.Fab")
		)
		(fp_line
			(start -0.2794 -0.1016)
			(end 0.2794 -0.1016)
			(stroke
				(width 0.1)
				(type default)
			)
			(layer "B.Fab")
		)
		(fp_line
			(start 0.2794 -0.1016)
			(end 0.2794 0.9906)
			(stroke
				(width 0.1)
				(type default)
			)
			(layer "B.Fab")
		)
		(pad "1" smd rect
			(at 0 0 90)
			(size 0.508 0.508)
			(layers "B.Cu" "B.Mask" "B.Paste")
			(net "PVPP_ABC")
		)
		(pad "2" smd rect
			(at 0 0.889 90)
			(size 0.508 0.508)
			(layers "B.Cu" "B.Mask" "B.Paste")
			(net "SMB_DDR_ABC_VPP_SCL_R")
		)
		(zone
			(layer "B.Cu")
			(hatch none 0.5)
			(connect_pads
				(clearance 0)
			)
			(min_thickness 0.25)
			(keepout
				(tracks not_allowed)
				(vias allowed)
				(pads allowed)
				(copperpour not_allowed)
				(footprints allowed)
			)
			(placement
				(enabled no)
				(sheetname "")
			)
			(fill
				(thermal_gap 0.5)
				(thermal_bridge_width 0.5)
				(island_removal_mode 0)
			)
			(polygon
				(pts
					(xy 323.2277 -28.11018) (xy 323.2277 -28.61818) (xy 323.6087 -28.61818) (xy 323.6087 -28.11018)
				)
			)
		)
		(zone
			(layer "B.Cu")
			(hatch none 0.5)
			(connect_pads
				(clearance 0)
			)
			(min_thickness 0.25)
			(keepout
				(tracks allowed)
				(vias not_allowed)
				(pads allowed)
				(copperpour not_allowed)
				(footprints allowed)
			)
			(placement
				(enabled no)
				(sheetname "")
			)
			(fill
				(thermal_gap 0.5)
				(thermal_bridge_width 0.5)
				(island_removal_mode 0)
			)
			(polygon
				(pts
					(xy 323.6087 -28.11018) (xy 323.6087 -28.61818) (xy 323.2277 -28.61818) (xy 323.2277 -28.11018)
				)
			)
		)
	)
	(footprint ""
		(layer "B.Cu")
		(at 430.0855 -13.716 -90)
		(property "Reference" "R9G33"
			(at 0 0 90)
			(layer "B.SilkS")
			(hide yes)
			(effects
				(font
					(size 1.27 1.27)
				)
				(justify mirror)
			)
		)
		(property "Value" ""
			(at 0 0 90)
			(layer "B.Fab")
			(effects
				(font
					(size 1.27 1.27)
				)
				(justify mirror)
			)
		)
		(duplicate_pad_numbers_are_jumpers no)
		(fp_poly
			(pts
				(xy 0.2794 -0.1016) (xy -0.2794 -0.1016) (xy -0.2794 0.9906) (xy 0.2794 0.9906)
			)
			(stroke
				(width 0)
				(type default)
			)
			(fill no)
			(layer "B.CrtYd")
		)
		(fp_line
			(start -0.2794 0.9906)
			(end -0.2794 -0.1016)
			(stroke
				(width 0.1)
				(type default)
			)
			(layer "B.Fab")
		)
		(fp_line
			(start 0.2794 0.9906)
			(end -0.2794 0.9906)
			(stroke
				(width 0.1)
				(type default)
			)
			(layer "B.Fab")
		)
		(fp_line
			(start -0.2794 -0.1016)
			(end 0.2794 -0.1016)
			(stroke
				(width 0.1)
				(type default)
			)
			(layer "B.Fab")
		)
		(fp_line
			(start 0.2794 -0.1016)
			(end 0.2794 0.9906)
			(stroke
				(width 0.1)
				(type default)
			)
			(layer "B.Fab")
		)
		(pad "1" smd rect
			(at 0 0 90)
			(size 0.508 0.508)
			(layers "B.Cu" "B.Mask" "B.Paste")
			(net "H_CPU0_DEF_MEMHOT_LVT3_R_N")
		)
		(pad "2" smd rect
			(at 0 0.889 90)
			(size 0.508 0.508)
			(layers "B.Cu" "B.Mask" "B.Paste")
			(net "H_CPU0_MEMDEF_MEMHOT_LVT3_K_N")
		)
		(zone
			(layer "B.Cu")
			(hatch none 0.5)
			(connect_pads
				(clearance 0)
			)
			(min_thickness 0.25)
			(keepout
				(tracks not_allowed)
				(vias allowed)
				(pads allowed)
				(copperpour not_allowed)
				(footprints allowed)
			)
			(placement
				(enabled no)
				(sheetname "")
			)
			(fill
				(thermal_gap 0.5)
				(thermal_bridge_width 0.5)
				(island_removal_mode 0)
			)
			(polygon
				(pts
					(xy 429.4505 -13.462) (xy 429.4505 -13.97) (xy 429.8315 -13.97) (xy 429.8315 -13.462)
				)
			)
		)
		(zone
			(layer "B.Cu")
			(hatch none 0.5)
			(connect_pads
				(clearance 0)
			)
			(min_thickness 0.25)
			(keepout
				(tracks allowed)
				(vias not_allowed)
				(pads allowed)
				(copperpour not_allowed)
				(footprints allowed)
			)
			(placement
				(enabled no)
				(sheetname "")
			)
			(fill
				(thermal_gap 0.5)
				(thermal_bridge_width 0.5)
				(island_removal_mode 0)
			)
			(polygon
				(pts
					(xy 429.8315 -13.462) (xy 429.8315 -13.97) (xy 429.4505 -13.97) (xy 429.4505 -13.462)
				)
			)
		)
	)
	(footprint ""
		(layer "B.Cu")
		(at 320.194432 -17.78 90)
		(property "Reference" "C4T5"
			(at 0 0 90)
			(layer "B.SilkS")
			(hide yes)
			(effects
				(font
					(size 1.27 1.27)
				)
				(justify mirror)
			)
		)
		(property "Value" ""
			(at 0 0 90)
			(layer "B.Fab")
			(effects
				(font
					(size 1.27 1.27)
				)
				(justify mirror)
			)
		)
		(duplicate_pad_numbers_are_jumpers no)
		(fp_poly
			(pts
				(xy 0.4953 -0.2032) (xy -0.4953 -0.2032) (xy -0.4953 1.6002) (xy 0.4953 1.6002)
			)
			(stroke
				(width 0)
				(type default)
			)
			(fill no)
			(layer "B.CrtYd")
		)
		(fp_line
			(start 0.4953 -0.2032)
			(end -0.4953 -0.2032)
			(stroke
				(width 0.1)
				(type default)
			)
			(layer "B.Fab")
		)
		(fp_line
			(start -0.4953 -0.2032)
			(end -0.4953 1.6002)
			(stroke
				(width 0.1)
				(type default)
			)
			(layer "B.Fab")
		)
		(fp_line
			(start 0.4953 1.6002)
			(end 0.4953 -0.2032)
			(stroke
				(width 0.1)
				(type default)
			)
			(layer "B.Fab")
		)
		(fp_line
			(start -0.4953 1.6002)
			(end 0.4953 1.6002)
			(stroke
				(width 0.1)
				(type default)
			)
			(layer "B.Fab")
		)
		(pad "1" smd rect
			(at 0 0 270)
			(size 0.762 0.889)
			(layers "B.Cu" "B.Mask" "B.Paste")
			(net "PVPP_ABC")
		)
		(pad "2" smd rect
			(at 0 1.397 270)
			(size 0.762 0.889)
			(layers "B.Cu" "B.Mask" "B.Paste")
			(net "GND")
		)
		(zone
			(layer "B.Cu")
			(hatch none 0.5)
			(connect_pads
				(clearance 0)
			)
			(min_thickness 0.25)
			(keepout
				(tracks not_allowed)
				(vias allowed)
				(pads allowed)
				(copperpour not_allowed)
				(footprints allowed)
			)
			(placement
				(enabled no)
				(sheetname "")
			)
			(fill
				(thermal_gap 0.5)
				(thermal_bridge_width 0.5)
				(island_removal_mode 0)
			)
			(polygon
				(pts
					(xy 320.638932 -18.161) (xy 320.638932 -17.399) (xy 321.146932 -17.399) (xy 321.146932 -18.161)
				)
			)
		)
	)
)
